# TIMECARD (Time Appliance Project (Time Card)) — schematic netlist excerpt (pin names and nets, part order shuffled) for the footprints in the layout excerpt that follows; sources: Cadence DE-HDL packaged netlist, KiCad conversion of R4006-B0001-02_R01.brd

C313  CAPACITOR  0.1UF 10V 10%  pkg SMC_0402R_H022  page 19 : \1\ = XP1R8V_ICP10100 ; \2\ = SG
L8  FERRITEBEAD  26OHM 25%  pkg SMC_0603R_H030  page 28 : \1\ = XP12R0V ; \2\ = VIN_XP3R3

(kicad_pcb
	(version 20260206)
	(generator "pcbnew")
	(generator_version "10.0")
	(general
		(thickness 1.6)
		(legacy_teardrops no)
	)
	(paper "A4")
	(title_block
		(title "timecard-production-celestica-r4006 — R4006-B0001-02_R01.brd")
		(comment 1 "Time Appliance Project (Time Card) / footprints 438-439 of 1113")
	)
	(layers
		(0 "F.Cu" signal "TOP")
		(4 "In1.Cu" signal "L02_GND1")
		(6 "In2.Cu" signal "L03_SIG1")
		(8 "In3.Cu" signal "L04_GND2")
		(10 "In4.Cu" signal "L05_VCC1")
		(12 "In5.Cu" signal "L06_VCC2")
		(14 "In6.Cu" signal "L07_GND3")
		(16 "In7.Cu" signal "L08_SIG2")
		(18 "In8.Cu" signal "L09_GND4")
		(2 "B.Cu" signal "BOTTOM")
		(9 "F.Adhes" user "F.Adhesive")
		(11 "B.Adhes" user "B.Adhesive")
		(13 "F.Paste" user "Package Geometry/Pastemask Top")
		(15 "B.Paste" user "Package Geometry/Pastemask Bottom")
		(5 "F.SilkS" user "Ref Des/Silkscreen Top")
		(7 "B.SilkS" user "Ref Des/Silkscreen Bottom")
		(1 "F.Mask" user "Board Geometry/Soldermask Top")
		(3 "B.Mask" user "Board Geometry/Soldermask Bottom")
		(17 "Dwgs.User" user "User.Drawings")
		(19 "Cmts.User" user "User.Comments")
		(21 "Eco1.User" user "User.Eco1")
		(23 "Eco2.User" user "User.Eco2")
		(25 "Edge.Cuts" user "Board Geometry/Outline")
		(27 "Margin" user)
		(31 "F.CrtYd" user "Package Geometry/Place Bound Top")
		(29 "B.CrtYd" user "Package Geometry/Place Bound Bottom")
		(35 "F.Fab" user "Ref Des/Assembly Top")
		(33 "B.Fab" user "Ref Des/Assembly Bottom")
	)
	(footprint ""
		(layer "F.Cu")
		(at 87.3252 -106.7308 180)
		(property "Reference" "L8"
			(at 0.889 1.30683 0)
			(unlocked yes)
			(layer "F.SilkS")
			(effects
				(font
					(size 0.7874 0.5842)
					(thickness 0.1524)
				)
				(justify left)
			)
		)
		(property "Value" "VAL*"
			(at -0.9398 3.70967 180)
			(unlocked yes)
			(layer "F.Fab")
			(hide yes)
			(effects
				(font
					(size 0.7874 0.5842)
					(thickness 0.1524)
				)
				(justify left)
			)
		)
		(property "Tolerance" "TOL*"
			(at -0.9906 5.00507 180)
			(unlocked yes)
			(layer "Cmts.User")
			(hide yes)
			(effects
				(font
					(size 0.7874 0.5842)
					(thickness 0.1524)
				)
				(justify left)
			)
		)
		(property "User Part Number" "PARTNUM*"
			(at -2.54 2.46507 180)
			(unlocked yes)
			(layer "Cmts.User")
			(hide yes)
			(effects
				(font
					(size 0.7874 0.5842)
					(thickness 0.1524)
				)
				(justify left)
			)
		)
		(property "Device Type" "FERRITEBEAD-G191-10101-01,26OHA"
			(at -0.9906 1.22047 180)
			(unlocked yes)
			(layer "F.Fab")
			(hide yes)
			(effects
				(font
					(size 0.7874 0.5842)
					(thickness 0.1524)
				)
				(justify left)
			)
		)
		(duplicate_pad_numbers_are_jumpers no)
		(fp_line
			(start 1.3208 0.7112)
			(end -1.3208 0.7112)
			(stroke
				(width 0.1)
				(type default)
			)
			(layer "F.SilkS")
		)
		(fp_line
			(start 1.3208 -0.7112)
			(end 1.3208 0.7112)
			(stroke
				(width 0.1)
				(type default)
			)
			(layer "F.SilkS")
		)
		(fp_line
			(start -1.3208 0.7112)
			(end -1.3208 -0.7112)
			(stroke
				(width 0.1)
				(type default)
			)
			(layer "F.SilkS")
		)
		(fp_line
			(start -1.3208 -0.7112)
			(end 1.3208 -0.7112)
			(stroke
				(width 0.1)
				(type default)
			)
			(layer "F.SilkS")
		)
		(fp_rect
			(start -1.3208 0.7112)
			(end 1.3208 -0.7112)
			(stroke
				(width 0)
				(type default)
			)
			(fill no)
			(layer "F.CrtYd")
		)
		(fp_line
			(start 0.8128 0.4572)
			(end -0.8128 0.4572)
			(stroke
				(width 0.1)
				(type default)
			)
			(layer "F.Fab")
		)
		(fp_line
			(start 0.8128 -0.4572)
			(end 0.8128 0.4572)
			(stroke
				(width 0.1)
				(type default)
			)
			(layer "F.Fab")
		)
		(fp_line
			(start -0.8128 0.4572)
			(end -0.8128 -0.4572)
			(stroke
				(width 0.1)
				(type default)
			)
			(layer "F.Fab")
		)
		(fp_line
			(start -0.8128 -0.4572)
			(end 0.8128 -0.4572)
			(stroke
				(width 0.1)
				(type default)
			)
			(layer "F.Fab")
		)
		(pad "1" smd rect
			(at -0.6858 0 180)
			(size 0.762 0.8636)
			(layers "F.Cu" "F.Mask" "F.Paste")
			(net "XP12R0V")
		)
		(pad "2" smd rect
			(at 0.6858 0 180)
			(size 0.762 0.8636)
			(layers "F.Cu" "F.Mask" "F.Paste")
			(net "VIN_XP3R3")
		)
		(zone
			(layer "F.Cu")
			(hatch none 0.5)
			(connect_pads
				(clearance 0)
			)
			(min_thickness 0.25)
			(keepout
				(tracks not_allowed)
				(vias allowed)
				(pads allowed)
				(copperpour not_allowed)
				(footprints allowed)
			)
			(placement
				(enabled no)
				(sheetname "")
			)
			(fill
				(thermal_gap 0.5)
				(thermal_bridge_width 0.5)
				(island_removal_mode 0)
			)
			(polygon
				(pts
					(xy 87.4776 -107.188) (xy 87.1728 -107.188) (xy 87.1728 -106.2736) (xy 87.4776 -106.2736)
				)
			)
		)
		(zone
			(layer "F.Cu")
			(hatch none 0.5)
			(connect_pads
				(clearance 0)
			)
			(min_thickness 0.25)
			(keepout
				(tracks allowed)
				(vias not_allowed)
				(pads allowed)
				(copperpour not_allowed)
				(footprints allowed)
			)
			(placement
				(enabled no)
				(sheetname "")
			)
			(fill
				(thermal_gap 0.5)
				(thermal_bridge_width 0.5)
				(island_removal_mode 0)
			)
			(polygon
				(pts
					(xy 87.4776 -107.188) (xy 87.1728 -107.188) (xy 87.1728 -106.2736) (xy 87.4776 -106.2736)
				)
			)
		)
	)
	(footprint ""
		(layer "F.Cu")
		(at 18.1356 -57.7342 -90)
		(property "Reference" "C313"
			(at -1.54305 1.3716 0)
			(unlocked yes)
			(layer "F.SilkS")
			(effects
				(font
					(size 0.635 0.4064)
					(thickness 0.1524)
				)
			)
		)
		(property "Value" "VAL*"
			(at 0.0762 2.067306 270)
			(unlocked yes)
			(layer "F.Fab")
			(hide yes)
			(effects
				(font
					(size 0.7874 0.5842)
					(thickness 0.1524)
				)
			)
		)
		(property "Tolerance" "TOL*"
			(at 0.0762 3.032506 270)
			(unlocked yes)
			(layer "Cmts.User")
			(hide yes)
			(effects
				(font
					(size 0.7874 0.5842)
					(thickness 0.1524)
				)
			)
		)
		(property "User Part Number" "PARTNUM*"
			(at 0.1016 4.023106 270)
			(unlocked yes)
			(layer "Cmts.User")
			(hide yes)
			(effects
				(font
					(size 0.7874 0.5842)
					(thickness 0.1524)
				)
			)
		)
		(property "Device Type" "CAPACITOR-G105-0B104-CK,0.1UF,A"
			(at 0.0508 1.127506 270)
			(unlocked yes)
			(layer "F.Fab")
			(hide yes)
			(effects
				(font
					(size 0.7874 0.5842)
					(thickness 0.1524)
				)
			)
		)
		(duplicate_pad_numbers_are_jumpers no)
		(fp_line
			(start -1.143 0.5588)
			(end 1.143 0.5588)
			(stroke
				(width 0.1)
				(type default)
			)
			(layer "F.SilkS")
		)
		(fp_line
			(start 1.143 0.5588)
			(end 1.143 -0.5588)
			(stroke
				(width 0.1)
				(type default)
			)
			(layer "F.SilkS")
		)
		(fp_line
			(start -1.143 -0.5588)
			(end -1.143 0.5588)
			(stroke
				(width 0.1)
				(type default)
			)
			(layer "F.SilkS")
		)
		(fp_line
			(start 1.143 -0.5588)
			(end -1.143 -0.5588)
			(stroke
				(width 0.1)
				(type default)
			)
			(layer "F.SilkS")
		)
		(fp_poly
			(pts
				(xy -1.143 0.5588) (xy 1.143 0.5588) (xy 1.143 -0.5588) (xy -1.143 -0.5588)
			)
			(stroke
				(width 0)
				(type default)
			)
			(fill no)
			(layer "F.CrtYd")
		)
		(fp_line
			(start -0.508 0.3048)
			(end 0.508 0.3048)
			(stroke
				(width 0.1)
				(type default)
			)
			(layer "F.Fab")
		)
		(fp_line
			(start 0.508 0.3048)
			(end 0.508 -0.3048)
			(stroke
				(width 0.1)
				(type default)
			)
			(layer "F.Fab")
		)
		(fp_line
			(start -0.508 -0.3048)
			(end -0.508 0.3048)
			(stroke
				(width 0.1)
				(type default)
			)
			(layer "F.Fab")
		)
		(fp_line
			(start 0.508 -0.3048)
			(end -0.508 -0.3048)
			(stroke
				(width 0.1)
				(type default)
			)
			(layer "F.Fab")
		)
		(pad "1" smd rect
			(at -0.5334 0 270)
			(size 0.7112 0.6096)
			(layers "F.Cu" "F.Mask" "F.Paste")
			(net "XP1R8V_ICP10100")
		)
		(pad "2" smd rect
			(at 0.5334 0 270)
			(size 0.7112 0.6096)
			(layers "F.Cu" "F.Mask" "F.Paste")
			(net "SG")
		)
		(zone
			(layer "F.Cu")
			(hatch none 0.5)
			(connect_pads
				(clearance 0)
			)
			(min_thickness 0.25)
			(keepout
				(tracks allowed)
				(vias not_allowed)
				(pads allowed)
				(copperpour not_allowed)
				(footprints allowed)
			)
			(placement
				(enabled no)
				(sheetname "")
			)
			(fill
				(thermal_gap 0.5)
				(thermal_bridge_width 0.5)
				(island_removal_mode 0)
			)
			(polygon
				(pts
					(xy 17.8308 -57.8104) (xy 17.8308 -57.658) (xy 18.4404 -57.658) (xy 18.4404 -57.8104)
				)
			)
		)
		(zone
			(layer "F.Cu")
			(hatch none 0.5)
			(connect_pads
				(clearance 0)
			)
			(min_thickness 0.25)
			(keepout
				(tracks not_allowed)
				(vias allowed)
				(pads allowed)
				(copperpour not_allowed)
				(footprints allowed)
			)
			(placement
				(enabled no)
				(sheetname "")
			)
			(fill
				(thermal_gap 0.5)
				(thermal_bridge_width 0.5)
				(island_removal_mode 0)
			)
			(polygon
				(pts
					(xy 17.8308 -57.8104) (xy 17.8308 -57.658) (xy 18.4404 -57.658) (xy 18.4404 -57.8104)
				)
			)
		)
	)
)
